FILE_TYPE=LIBRARY_PARTS;
primitive 'DS125BR111RTWR';
  pin
    'EQB0||AD3':
      PIN_NUMBER='(1)';
      INPUT_LOAD='(-0.01,0.01)';
    'EQB1||AD2':
      PIN_NUMBER='(2)';
      INPUT_LOAD='(-0.01,0.01)';
    'ENSMB':
      PIN_NUMBER='(3)';
      INPUT_LOAD='(-0.01,0.01)';
    'SDA||VODA_DB':
      PIN_NUMBER='(4)';
      BIDIRECTIONAL='TRUE';
      INPUT_LOAD='(-0.01,0.01)';
      OUTPUT_LOAD='(1.0,-1.0)';
    'SCL||VODB_DB':
      PIN_NUMBER='(5)';
      BIDIRECTIONAL='TRUE';
      INPUT_LOAD='(-0.01,0.01)';
      OUTPUT_LOAD='(1.0,-1.0)';
    'PWDN':
      PIN_NUMBER='(6)';
      INPUT_LOAD='(-0.01,0.01)';
    'OUTA+':
      PIN_NUMBER='(7)';
      OUTPUT_LOAD='(1.0,-1.0)';
    'OUTA-':
      PIN_NUMBER='(8)';
      OUTPUT_LOAD='(1.0,-1.0)';
    'EQA1||AD1':
      PIN_NUMBER='(9)';
      INPUT_LOAD='(-0.01,0.01)';
    'EQA0||AD0':
      PIN_NUMBER='(10)';
      INPUT_LOAD='(-0.01,0.01)';
    'INB+':
      PIN_NUMBER='(11)';
      INPUT_LOAD='(-0.01,0.01)';
    'INB-':
      PIN_NUMBER='(12)';
      INPUT_LOAD='(-0.01,0.01)';
    'RES':
      PIN_NUMBER='(13)';
      INPUT_LOAD='(-0.01,0.01)';
    'SD_TH':
      PIN_NUMBER='(14)';
      INPUT_LOAD='(-0.01,0.01)';
    'VIN':
      PIN_NUMBER='(15)';
      PINUSE='POWER';
      NO_LOAD_CHECK='Both';
      NO_IO_CHECK='Both';
      NO_ASSERT_CHECK='TRUE';
      NO_DIR_CHECK='TRUE';
      ALLOW_CONNECT='TRUE';
    'VDD_SEL':
      PIN_NUMBER='(16)';
      INPUT_LOAD='(-0.01,0.01)';
    'VOD_SEL||READEN#':
      PIN_NUMBER='(17)';
      INPUT_LOAD='(-0.01,0.01)';
    'RXDET||DONE#':
      PIN_NUMBER='(18)';
      BIDIRECTIONAL='TRUE';
      INPUT_LOAD='(-0.01,0.01)';
      OUTPUT_LOAD='(1.0,-1.0)';
    'OUTB-':
      PIN_NUMBER='(19)';
      OUTPUT_LOAD='(1.0,-1.0)';
    'OUTB+':
      PIN_NUMBER='(20)';
      OUTPUT_LOAD='(1.0,-1.0)';
    'VDD_21':
      PIN_NUMBER='(21)';
      PINUSE='POWER';
      NO_LOAD_CHECK='Both';
      NO_IO_CHECK='Both';
      NO_ASSERT_CHECK='TRUE';
      NO_DIR_CHECK='TRUE';
      ALLOW_CONNECT='TRUE';
    'VDD_22':
      PIN_NUMBER='(22)';
      PINUSE='POWER';
      NO_LOAD_CHECK='Both';
      NO_IO_CHECK='Both';
      NO_ASSERT_CHECK='TRUE';
      NO_DIR_CHECK='TRUE';
      ALLOW_CONNECT='TRUE';
    'INA-':
      PIN_NUMBER='(23)';
      INPUT_LOAD='(-0.01,0.01)';
    'INA+':
      PIN_NUMBER='(24)';
      INPUT_LOAD='(-0.01,0.01)';
    'TH_GND':
      PIN_NUMBER='(25)';
      PINUSE='POWER';
      NO_LOAD_CHECK='Both';
      NO_IO_CHECK='Both';
      NO_ASSERT_CHECK='TRUE';
      NO_DIR_CHECK='TRUE';
      ALLOW_CONNECT='TRUE';
  end_pin;
  body
    PART_NAME='DS125BR111RTWR';
    BODY_NAME='DS125BR111RTWR';
    PHYS_DES_PREFIX='U';
    CLASS='IC';
  end_body;
end_primitive;

END.
